(kicad_pcb
	(version 20221018)
	(generator pcbnew)
	(general
    (thickness 1.62)
  )
	(paper "A4")
	(title_block
    (title "ECP5 - Datacenter Secure Control Module (DC-SCM)")
    (date "2024-07-01")
    (rev "1.2.1")
		(comment 9 "footprints 238-246 of 506")
	)
	(layers
    (0 "F.Cu" signal)
    (1 "In1.Cu" power)
    (2 "In2.Cu" signal)
    (3 "In3.Cu" power)
    (4 "In4.Cu" power)
    (5 "In5.Cu" signal)
    (6 "In6.Cu" power)
    (31 "B.Cu" signal)
    (32 "B.Adhes" user "B.Adhesive")
    (33 "F.Adhes" user "F.Adhesive")
    (34 "B.Paste" user)
    (35 "F.Paste" user)
    (36 "B.SilkS" user "B.Silkscreen")
    (37 "F.SilkS" user "F.Silkscreen")
    (38 "B.Mask" user)
    (39 "F.Mask" user)
    (40 "Dwgs.User" user "User.Drawings")
    (41 "Cmts.User" user "User.Comments")
    (42 "Eco1.User" user "User.Eco1")
    (43 "Eco2.User" user "User.Eco2")
    (44 "Edge.Cuts" user)
    (45 "Margin" user)
    (46 "B.CrtYd" user "B.Courtyard")
    (47 "F.CrtYd" user "F.Courtyard")
    (48 "B.Fab" user)
    (49 "F.Fab" user)
  )
	(footprint "antmicro-footprints:R_0402_1005Metric" (layer "B.Cu")
    (at 94.55 100.6 180)
    (descr "Resistor SMD 0402")
    (tags "resistor SMD 0402")
    (property "Author" "Antmicro")
    (property "License" "Apache-2.0")
    (property "MPN" "CR0402-FX-4702GLF")
    (property "Manufacturer" "Bourns")
    (property "Public" "False")
    (property "Sheetfile" "interfaces.kicad_sch")
    (property "Sheetname" "Interfaces")
    (property "Tolerance" "1%")
    (property "Val" "47k")
    (property "ki_description" "SMD Chip Resistor, 47 kohm, ± 1%, 62.5 mW, 0402 [1005 Metric], Thick Film, General Purpose")
    (property "ki_keywords" "0402, SMT, RESISTOR, PASSIVE")
    (attr smd)
    (fp_text reference "R64" (at 0 -6.776) (layer "B.SilkS")
        (effects (font (size 0.7 0.7) (thickness 0.127)) (justify mirror))
    )
    (fp_text value "R_47k_0402" (at 0 -1.17) (layer "B.Fab")
        (effects (font (size 1 1) (thickness 0.15)) (justify mirror))
    )
    (fp_text user "${REFERENCE}" (at 0 0) (layer "B.Fab")
        (effects (font (size 0.25 0.25) (thickness 0.04)) (justify mirror))
    )
    (fp_text user "Author: Antmicro" (at -0.95 -4.169) (layer "B.Fab") hide
        (effects (font (size 0.7 0.7) (thickness 0.15)) (justify left bottom mirror))
    )
    (fp_text user "License: Apache-2.0" (at -0.95 -5.169) (layer "B.Fab") hide
        (effects (font (size 0.7 0.7) (thickness 0.15)) (justify left bottom mirror))
    )
    (fp_rect (start -0.925 0.47) (end 0.925 -0.47)
      (stroke (width 0.05) (type default)) (fill none) (layer "B.CrtYd"))
    (fp_rect (start -0.5 0.25) (end 0.5 -0.25)
      (stroke (width 0.15) (type solid)) (fill none) (layer "B.Fab"))
    (pad "1" smd roundrect (at -0.48 0 180) (size 0.59 0.64) (layers "B.Cu" "B.Paste" "B.Mask") (roundrect_rratio 0.25)
      (net 2 "VCC3V3") (pintype "passive"))
    (pad "2" smd roundrect (at 0.48 0 180) (size 0.59 0.64) (layers "B.Cu" "B.Paste" "B.Mask") (roundrect_rratio 0.25)
      (net 282 "MMC_DAT3") (pintype "passive"))
  )
	(footprint "antmicro-footprints:R_0402_1005Metric" (layer "B.Cu")
    (at 88.6 100.6)
    (descr "Resistor SMD 0402")
    (tags "resistor SMD 0402")
    (property "Author" "Antmicro")
    (property "License" "Apache-2.0")
    (property "MPN" "CR0402-FX-4702GLF")
    (property "Manufacturer" "Bourns")
    (property "Public" "False")
    (property "Sheetfile" "interfaces.kicad_sch")
    (property "Sheetname" "Interfaces")
    (property "Tolerance" "1%")
    (property "Val" "47k")
    (property "ki_description" "SMD Chip Resistor, 47 kohm, ± 1%, 62.5 mW, 0402 [1005 Metric], Thick Film, General Purpose")
    (property "ki_keywords" "0402, SMT, RESISTOR, PASSIVE")
    (attr smd)
    (fp_text reference "R63" (at 0.1 2.07) (layer "B.SilkS")
        (effects (font (size 0.7 0.7) (thickness 0.127)) (justify mirror))
    )
    (fp_text value "R_47k_0402" (at 0 -1.17) (layer "B.Fab")
        (effects (font (size 1 1) (thickness 0.15)) (justify mirror))
    )
    (fp_text user "${REFERENCE}" (at 0 0) (layer "B.Fab")
        (effects (font (size 0.25 0.25) (thickness 0.04)) (justify mirror))
    )
    (fp_text user "Author: Antmicro" (at -0.95 -4.169 180) (layer "B.Fab") hide
        (effects (font (size 0.7 0.7) (thickness 0.15)) (justify left bottom mirror))
    )
    (fp_text user "License: Apache-2.0" (at -0.95 -5.169 180) (layer "B.Fab") hide
        (effects (font (size 0.7 0.7) (thickness 0.15)) (justify left bottom mirror))
    )
    (fp_rect (start -0.925 0.47) (end 0.925 -0.47)
      (stroke (width 0.05) (type default)) (fill none) (layer "B.CrtYd"))
    (fp_rect (start -0.5 0.25) (end 0.5 -0.25)
      (stroke (width 0.15) (type solid)) (fill none) (layer "B.Fab"))
    (pad "1" smd roundrect (at -0.48 0) (size 0.59 0.64) (layers "B.Cu" "B.Paste" "B.Mask") (roundrect_rratio 0.25)
      (net 2 "VCC3V3") (pintype "passive"))
    (pad "2" smd roundrect (at 0.48 0) (size 0.59 0.64) (layers "B.Cu" "B.Paste" "B.Mask") (roundrect_rratio 0.25)
      (net 281 "MMC_DAT2") (pintype "passive"))
  )
	(footprint "antmicro-footprints:R_0402_1005Metric" (layer "B.Cu")
    (at 88.6 101.6)
    (descr "Resistor SMD 0402")
    (tags "resistor SMD 0402")
    (property "Author" "Antmicro")
    (property "License" "Apache-2.0")
    (property "MPN" "CR0402-FX-4702GLF")
    (property "Manufacturer" "Bourns")
    (property "Public" "False")
    (property "Sheetfile" "interfaces.kicad_sch")
    (property "Sheetname" "Interfaces")
    (property "Tolerance" "1%")
    (property "Val" "47k")
    (property "ki_description" "SMD Chip Resistor, 47 kohm, ± 1%, 62.5 mW, 0402 [1005 Metric], Thick Film, General Purpose")
    (property "ki_keywords" "0402, SMT, RESISTOR, PASSIVE")
    (attr smd)
    (fp_text reference "R61" (at 0.1 2.07) (layer "B.SilkS")
        (effects (font (size 0.7 0.7) (thickness 0.127)) (justify mirror))
    )
    (fp_text value "R_47k_0402" (at 0 -1.17) (layer "B.Fab")
        (effects (font (size 1 1) (thickness 0.15)) (justify mirror))
    )
    (fp_text user "Author: Antmicro" (at -0.95 -4.169 180) (layer "B.Fab") hide
        (effects (font (size 0.7 0.7) (thickness 0.15)) (justify left bottom mirror))
    )
    (fp_text user "${REFERENCE}" (at 0 0) (layer "B.Fab")
        (effects (font (size 0.25 0.25) (thickness 0.04)) (justify mirror))
    )
    (fp_text user "License: Apache-2.0" (at -0.95 -5.169 180) (layer "B.Fab") hide
        (effects (font (size 0.7 0.7) (thickness 0.15)) (justify left bottom mirror))
    )
    (fp_rect (start -0.925 0.47) (end 0.925 -0.47)
      (stroke (width 0.05) (type default)) (fill none) (layer "B.CrtYd"))
    (fp_rect (start -0.5 0.25) (end 0.5 -0.25)
      (stroke (width 0.15) (type solid)) (fill none) (layer "B.Fab"))
    (pad "1" smd roundrect (at -0.48 0) (size 0.59 0.64) (layers "B.Cu" "B.Paste" "B.Mask") (roundrect_rratio 0.25)
      (net 2 "VCC3V3") (pintype "passive"))
    (pad "2" smd roundrect (at 0.48 0) (size 0.59 0.64) (layers "B.Cu" "B.Paste" "B.Mask") (roundrect_rratio 0.25)
      (net 279 "MMC_DAT0") (pintype "passive"))
  )
	(footprint "antmicro-footprints:C_0603_1608Metric" (layer "B.Cu")
    (at 90.8 98.6 -90)
    (descr "Capacitor SMD 0603")
    (tags "capacitor 0603")
    (property "Author" "Antmicro")
    (property "Dielectric" "")
    (property "License" "Apache-2.0")
    (property "MPN" "GRM188R60J226MEA0D")
    (property "Manufacturer" "Murata")
    (property "Public" "False")
    (property "Sheetfile" "interfaces.kicad_sch")
    (property "Sheetname" "Interfaces")
    (property "Val" "22u")
    (property "Voltage" "")
    (property "ki_description" "SMD Multilayer Ceramic Capacitor, 22 µF, 6.3 V, 0603 [1608 Metric], ± 20%, X5R, GRM Series")
    (property "ki_keywords" "0603, SMT, CAPACITOR, PASSIVE, CERAMIC, MLCC")
    (attr smd)
    (fp_text reference "C50" (at -0.205 -1.1 90) (layer "B.SilkS")
        (effects (font (size 0.7 0.7) (thickness 0.127)) (justify mirror))
    )
    (fp_text value "C_22u_0603" (at 0 -1.9 90) (layer "B.Fab")
        (effects (font (size 1 1) (thickness 0.15)) (justify mirror))
    )
    (fp_text user "Author: Antmicro" (at -1.682 -4.894 90) (layer "B.Fab") hide
        (effects (font (size 0.7 0.7) (thickness 0.15)) (justify left bottom mirror))
    )
    (fp_text user "License: Apache-2.0" (at -1.682 -5.895 90) (layer "B.Fab") hide
        (effects (font (size 0.7 0.7) (thickness 0.15)) (justify left bottom mirror))
    )
    (fp_text user "${REFERENCE}" (at -1.682 -3.895 90) (layer "B.Fab") hide
        (effects (font (size 0.7 0.7) (thickness 0.15)) (justify left bottom mirror))
    )
    (fp_line (start -0.15 -0.4) (end 0.15 -0.4)
      (stroke (width 0.15) (type solid)) (layer "B.SilkS"))
    (fp_line (start -0.15 0.4) (end 0.15 0.4)
      (stroke (width 0.15) (type solid)) (layer "B.SilkS"))
    (fp_rect (start -1.25 0.65) (end 1.25 -0.65)
      (stroke (width 0.05) (type solid)) (fill none) (layer "B.CrtYd"))
    (fp_rect (start -0.8 0.4) (end 0.8 -0.4)
      (stroke (width 0.15) (type solid)) (fill none) (layer "B.Fab"))
    (pad "1" smd roundrect (at -0.7 0 270) (size 0.8 1) (layers "B.Cu" "B.Paste" "B.Mask") (roundrect_rratio 0.2)
      (net 1 "GND") (pintype "passive"))
    (pad "2" smd roundrect (at 0.7 0 270) (size 0.8 1) (layers "B.Cu" "B.Paste" "B.Mask") (roundrect_rratio 0.2)
      (net 2 "VCC3V3") (pintype "passive"))
  )
	(footprint "antmicro-footprints:C_0603_1608Metric" (layer "B.Cu")
    (at 85.9 102.8 180)
    (descr "Capacitor SMD 0603")
    (tags "capacitor 0603")
    (property "Author" "Antmicro")
    (property "Dielectric" "")
    (property "License" "Apache-2.0")
    (property "MPN" "GRM188R60J226MEA0D")
    (property "Manufacturer" "Murata")
    (property "Public" "False")
    (property "Sheetfile" "interfaces.kicad_sch")
    (property "Sheetname" "Interfaces")
    (property "Val" "22u")
    (property "Voltage" "")
    (property "ki_description" "SMD Multilayer Ceramic Capacitor, 22 µF, 6.3 V, 0603 [1608 Metric], ± 20%, X5R, GRM Series")
    (property "ki_keywords" "0603, SMT, CAPACITOR, PASSIVE, CERAMIC, MLCC")
    (attr smd)
    (fp_text reference "C48" (at 0.03 -1.185) (layer "B.SilkS")
        (effects (font (size 0.7 0.7) (thickness 0.127)) (justify mirror))
    )
    (fp_text value "C_22u_0603" (at 0 -1.9) (layer "B.Fab")
        (effects (font (size 1 1) (thickness 0.15)) (justify mirror))
    )
    (fp_text user "${REFERENCE}" (at -1.682 -3.895) (layer "B.Fab") hide
        (effects (font (size 0.7 0.7) (thickness 0.15)) (justify left bottom mirror))
    )
    (fp_text user "Author: Antmicro" (at -1.682 -4.894) (layer "B.Fab") hide
        (effects (font (size 0.7 0.7) (thickness 0.15)) (justify left bottom mirror))
    )
    (fp_text user "License: Apache-2.0" (at -1.682 -5.895) (layer "B.Fab") hide
        (effects (font (size 0.7 0.7) (thickness 0.15)) (justify left bottom mirror))
    )
    (fp_line (start -0.15 -0.4) (end 0.15 -0.4)
      (stroke (width 0.15) (type solid)) (layer "B.SilkS"))
    (fp_line (start -0.15 0.4) (end 0.15 0.4)
      (stroke (width 0.15) (type solid)) (layer "B.SilkS"))
    (fp_rect (start -1.25 0.65) (end 1.25 -0.65)
      (stroke (width 0.05) (type solid)) (fill none) (layer "B.CrtYd"))
    (fp_rect (start -0.8 0.4) (end 0.8 -0.4)
      (stroke (width 0.15) (type solid)) (fill none) (layer "B.Fab"))
    (pad "1" smd roundrect (at -0.7 0 180) (size 0.8 1) (layers "B.Cu" "B.Paste" "B.Mask") (roundrect_rratio 0.2)
      (net 1 "GND") (pintype "passive"))
    (pad "2" smd roundrect (at 0.7 0 180) (size 0.8 1) (layers "B.Cu" "B.Paste" "B.Mask") (roundrect_rratio 0.2)
      (net 2 "VCC3V3") (pintype "passive"))
  )
	(footprint "antmicro-footprints:C_0402_1005Metric" (layer "B.Cu")
    (at 85.8 95.6 180)
    (descr "Capacitor SMD 0402")
    (tags "capacitor SMD 0402")
    (property "Author" "Antmicro")
    (property "Dielectric" "X5R")
    (property "License" "Apache-2.0")
    (property "MPN" "GRM155R61H104KE14D")
    (property "Manufacturer" "Murata")
    (property "Public" "False")
    (property "Sheetfile" "interfaces.kicad_sch")
    (property "Sheetname" "Interfaces")
    (property "Val" "100n")
    (property "Voltage" "50V")
    (property "ki_description" "SMD Multilayer Ceramic Capacitor, 0.1 µF, 50 V, 0402 [1005 Metric], ± 10%, X5R, GRM Series")
    (property "ki_keywords" "0402, SMT, CAPACITOR, PASSIVE, CERAMIC, MLCC")
    (attr smd)
    (fp_text reference "C51" (at 0.4 9.42375) (layer "B.SilkS")
        (effects (font (size 0.7 0.7) (thickness 0.127)) (justify mirror))
    )
    (fp_text value "C_100n_0402" (at 0 -1.17) (layer "B.Fab")
        (effects (font (size 1 1) (thickness 0.15)) (justify mirror))
    )
    (fp_text user "Author: Antmicro" (at -0.939 -3.399) (layer "B.Fab") hide
        (effects (font (size 0.7 0.7) (thickness 0.15)) (justify left bottom mirror))
    )
    (fp_text user "${REFERENCE}" (at 0 0) (layer "B.Fab")
        (effects (font (size 0.25 0.25) (thickness 0.04)) (justify mirror))
    )
    (fp_text user "License: Apache-2.0" (at -0.939 -5.799) (layer "B.Fab") hide
        (effects (font (size 0.7 0.7) (thickness 0.15)) (justify left bottom mirror))
    )
    (fp_rect (start -0.925 0.47) (end 0.925 -0.47)
      (stroke (width 0.05) (type default)) (fill none) (layer "B.CrtYd"))
    (fp_line (start -0.494 -0.248) (end -0.494 0.25)
      (stroke (width 0.15) (type solid)) (layer "B.Fab"))
    (fp_line (start -0.494 0.25) (end 0.504 0.25)
      (stroke (width 0.15) (type solid)) (layer "B.Fab"))
    (fp_line (start 0.504 -0.248) (end -0.494 -0.248)
      (stroke (width 0.15) (type solid)) (layer "B.Fab"))
    (fp_line (start 0.504 0.25) (end 0.504 -0.248)
      (stroke (width 0.15) (type solid)) (layer "B.Fab"))
    (pad "1" smd roundrect (at -0.48 0 180) (size 0.59 0.64) (layers "B.Cu" "B.Paste" "B.Mask") (roundrect_rratio 0.25)
      (net 1 "GND") (pintype "passive"))
    (pad "2" smd roundrect (at 0.48 0 180) (size 0.59 0.64) (layers "B.Cu" "B.Paste" "B.Mask") (roundrect_rratio 0.25)
      (net 2 "VCC3V3") (pintype "passive"))
  )
	(footprint "antmicro-footprints:C_0402_1005Metric" (layer "B.Cu")
    (at 85.8 97.6 180)
    (descr "Capacitor SMD 0402")
    (tags "capacitor SMD 0402")
    (property "Author" "Antmicro")
    (property "Dielectric" "X5R")
    (property "License" "Apache-2.0")
    (property "MPN" "GRM155R61H104KE14D")
    (property "Manufacturer" "Murata")
    (property "Public" "False")
    (property "Sheetfile" "interfaces.kicad_sch")
    (property "Sheetname" "Interfaces")
    (property "Val" "100n")
    (property "Voltage" "50V")
    (property "ki_description" "SMD Multilayer Ceramic Capacitor, 0.1 µF, 50 V, 0402 [1005 Metric], ± 10%, X5R, GRM Series")
    (property "ki_keywords" "0402, SMT, CAPACITOR, PASSIVE, CERAMIC, MLCC")
    (attr smd)
    (fp_text reference "C52" (at 0.4 9.33125) (layer "B.SilkS")
        (effects (font (size 0.7 0.7) (thickness 0.127)) (justify mirror))
    )
    (fp_text value "C_100n_0402" (at 0 -1.17) (layer "B.Fab")
        (effects (font (size 1 1) (thickness 0.15)) (justify mirror))
    )
    (fp_text user "License: Apache-2.0" (at -0.939 -5.799) (layer "B.Fab") hide
        (effects (font (size 0.7 0.7) (thickness 0.15)) (justify left bottom mirror))
    )
    (fp_text user "${REFERENCE}" (at 0 0) (layer "B.Fab")
        (effects (font (size 0.25 0.25) (thickness 0.04)) (justify mirror))
    )
    (fp_text user "Author: Antmicro" (at -0.939 -3.399) (layer "B.Fab") hide
        (effects (font (size 0.7 0.7) (thickness 0.15)) (justify left bottom mirror))
    )
    (fp_rect (start -0.925 0.47) (end 0.925 -0.47)
      (stroke (width 0.05) (type default)) (fill none) (layer "B.CrtYd"))
    (fp_line (start -0.494 -0.248) (end -0.494 0.25)
      (stroke (width 0.15) (type solid)) (layer "B.Fab"))
    (fp_line (start -0.494 0.25) (end 0.504 0.25)
      (stroke (width 0.15) (type solid)) (layer "B.Fab"))
    (fp_line (start 0.504 -0.248) (end -0.494 -0.248)
      (stroke (width 0.15) (type solid)) (layer "B.Fab"))
    (fp_line (start 0.504 0.25) (end 0.504 -0.248)
      (stroke (width 0.15) (type solid)) (layer "B.Fab"))
    (pad "1" smd roundrect (at -0.48 0 180) (size 0.59 0.64) (layers "B.Cu" "B.Paste" "B.Mask") (roundrect_rratio 0.25)
      (net 1 "GND") (pintype "passive"))
    (pad "2" smd roundrect (at 0.48 0 180) (size 0.59 0.64) (layers "B.Cu" "B.Paste" "B.Mask") (roundrect_rratio 0.25)
      (net 2 "VCC3V3") (pintype "passive"))
  )
	(footprint "antmicro-footprints:C_0402_1005Metric" (layer "B.Cu")
    (at 83.31 100.22 90)
    (descr "Capacitor SMD 0402")
    (tags "capacitor SMD 0402")
    (property "Author" "Antmicro")
    (property "Dielectric" "")
    (property "License" "Apache-2.0")
    (property "MPN" "GRM155R61A475MEAAD")
    (property "Manufacturer" "Murata")
    (property "Public" "False")
    (property "Sheetfile" "interfaces.kicad_sch")
    (property "Sheetname" "Interfaces")
    (property "Val" "4u7")
    (property "Voltage" "")
    (property "ki_description" "SMD Multilayer Ceramic Capacitor, 4.7 µF, 10 V, 0402 [1005 Metric], ± 20%, X5R, GRM Series")
    (property "ki_keywords" "0402, SMT, CAPACITOR, PASSIVE")
    (attr smd)
    (fp_text reference "C53" (at 0 1.17 90) (layer "B.SilkS")
        (effects (font (size 0.7 0.7) (thickness 0.127)) (justify mirror))
    )
    (fp_text value "C_4u7_0402" (at 0 -1.17 90) (layer "B.Fab")
        (effects (font (size 1 1) (thickness 0.15)) (justify mirror))
    )
    (fp_text user "License: Apache-2.0" (at -0.939 -5.799 270) (layer "B.Fab") hide
        (effects (font (size 0.7 0.7) (thickness 0.15)) (justify left bottom mirror))
    )
    (fp_text user "${REFERENCE}" (at 0 0 90) (layer "B.Fab")
        (effects (font (size 0.25 0.25) (thickness 0.04)) (justify mirror))
    )
    (fp_text user "Author: Antmicro" (at -0.939 -3.399 270) (layer "B.Fab") hide
        (effects (font (size 0.7 0.7) (thickness 0.15)) (justify left bottom mirror))
    )
    (fp_rect (start -0.925 0.47) (end 0.925 -0.47)
      (stroke (width 0.05) (type default)) (fill none) (layer "B.CrtYd"))
    (fp_line (start -0.494 -0.248) (end -0.494 0.25)
      (stroke (width 0.15) (type solid)) (layer "B.Fab"))
    (fp_line (start -0.494 0.25) (end 0.504 0.25)
      (stroke (width 0.15) (type solid)) (layer "B.Fab"))
    (fp_line (start 0.504 -0.248) (end -0.494 -0.248)
      (stroke (width 0.15) (type solid)) (layer "B.Fab"))
    (fp_line (start 0.504 0.25) (end 0.504 -0.248)
      (stroke (width 0.15) (type solid)) (layer "B.Fab"))
    (pad "1" smd roundrect (at -0.48 0 90) (size 0.59 0.64) (layers "B.Cu" "B.Paste" "B.Mask") (roundrect_rratio 0.25)
      (net 1 "GND") (pintype "passive"))
    (pad "2" smd roundrect (at 0.48 0 90) (size 0.59 0.64) (layers "B.Cu" "B.Paste" "B.Mask") (roundrect_rratio 0.25)
      (net 219 "Net-(U6-VDDIM)") (pintype "passive"))
  )
	(footprint "antmicro-footprints:C_0402_1005Metric" (layer "B.Cu")
    (at 123.355 118.335 -90)
    (descr "Capacitor SMD 0402")
    (tags "capacitor SMD 0402")
    (property "Author" "Antmicro")
    (property "Dielectric" "X5R")
    (property "License" "Apache-2.0")
    (property "MPN" "GRM155R61H104KE14D")
    (property "Manufacturer" "Murata")
    (property "Public" "False")
    (property "Sheetfile" "interfaces.kicad_sch")
    (property "Sheetname" "Interfaces")
    (property "Val" "100n")
    (property "Voltage" "50V")
    (property "ki_description" "SMD Multilayer Ceramic Capacitor, 0.1 µF, 50 V, 0402 [1005 Metric], ± 10%, X5R, GRM Series")
    (property "ki_keywords" "0402, SMT, CAPACITOR, PASSIVE, CERAMIC, MLCC")
    (attr smd)
    (fp_text reference "C64" (at 1.93 -0.065 90) (layer "B.SilkS")
        (effects (font (size 0.7 0.7) (thickness 0.127)) (justify mirror))
    )
    (fp_text value "C_100n_0402" (at 0 -1.17 90) (layer "B.Fab")
        (effects (font (size 1 1) (thickness 0.15)) (justify mirror))
    )
    (fp_text user "License: Apache-2.0" (at -0.939 -5.799 90) (layer "B.Fab") hide
        (effects (font (size 0.7 0.7) (thickness 0.15)) (justify left bottom mirror))
    )
    (fp_text user "${REFERENCE}" (at 0 0 90) (layer "B.Fab")
        (effects (font (size 0.25 0.25) (thickness 0.04)) (justify mirror))
    )
    (fp_text user "Author: Antmicro" (at -0.939 -3.399 90) (layer "B.Fab") hide
        (effects (font (size 0.7 0.7) (thickness 0.15)) (justify left bottom mirror))
    )
    (fp_rect (start -0.925 0.47) (end 0.925 -0.47)
      (stroke (width 0.05) (type default)) (fill none) (layer "B.CrtYd"))
    (fp_line (start -0.494 -0.248) (end -0.494 0.25)
      (stroke (width 0.15) (type solid)) (layer "B.Fab"))
    (fp_line (start -0.494 0.25) (end 0.504 0.25)
      (stroke (width 0.15) (type solid)) (layer "B.Fab"))
    (fp_line (start 0.504 -0.248) (end -0.494 -0.248)
      (stroke (width 0.15) (type solid)) (layer "B.Fab"))
    (fp_line (start 0.504 0.25) (end 0.504 -0.248)
      (stroke (width 0.15) (type solid)) (layer "B.Fab"))
    (pad "1" smd roundrect (at -0.48 0 270) (size 0.59 0.64) (layers "B.Cu" "B.Paste" "B.Mask") (roundrect_rratio 0.25)
      (net 2 "VCC3V3") (pintype "passive"))
    (pad "2" smd roundrect (at 0.48 0 270) (size 0.59 0.64) (layers "B.Cu" "B.Paste" "B.Mask") (roundrect_rratio 0.25)
      (net 1 "GND") (pintype "passive"))
  )
)
